(kicad_pcb
	(version 20260206)
	(generator "pcbnew")
	(generator_version "10.0")
	(general
		(thickness 1.6)
		(legacy_teardrops no)
	)
	(paper "A4")
	(title_block
		(title "03242023_DA0F0TMBIJ0_F0T_Motherboard_J_brd_V01_OCP.brd")
		(comment 1 "Grand Teton / footprints 5275-5282 of 6105")
	)
	(layers
		(0 "F.Cu" signal "TOP")
		(4 "In1.Cu" signal "GND")
		(6 "In2.Cu" signal "IN1")
		(8 "In3.Cu" signal "GND1")
		(10 "In4.Cu" signal "IN2")
		(12 "In5.Cu" signal "GND2")
		(14 "In6.Cu" signal "IN3")
		(16 "In7.Cu" signal "GND3")
		(18 "In8.Cu" signal "VCC")
		(20 "In9.Cu" signal "VCC1")
		(22 "In10.Cu" signal "GND4")
		(24 "In11.Cu" signal "IN4")
		(26 "In12.Cu" signal "GND5")
		(28 "In13.Cu" signal "IN5")
		(30 "In14.Cu" signal "GND6")
		(32 "In15.Cu" signal "IN6")
		(34 "In16.Cu" signal "GND7")
		(2 "B.Cu" signal "BOTTOM")
		(9 "F.Adhes" user "F.Adhesive")
		(11 "B.Adhes" user "B.Adhesive")
		(13 "F.Paste" user "Package Geometry/Pastemask Top")
		(15 "B.Paste" user "Package Geometry/Pastemask Bottom")
		(5 "F.SilkS" user "Ref Des/Silkscreen Top")
		(7 "B.SilkS" user "Ref Des/Silkscreen Bottom")
		(1 "F.Mask" user "Board Geometry/Soldermask Top")
		(3 "B.Mask" user "Board Geometry/Soldermask Bottom")
		(17 "Dwgs.User" user "User.Drawings")
		(19 "Cmts.User" user "User.Comments")
		(21 "Eco1.User" user "User.Eco1")
		(23 "Eco2.User" user "User.Eco2")
		(25 "Edge.Cuts" user "Board Geometry/Outline")
		(27 "Margin" user)
		(31 "F.CrtYd" user "Package Geometry/Place Bound Top")
		(29 "B.CrtYd" user "Package Geometry/Place Bound Bottom")
		(35 "F.Fab" user "Ref Des/Assembly Top")
		(33 "B.Fab" user "Ref Des/Assembly Bottom")
	)
	(footprint ""
		(layer "B.Cu")
		(at 30.163516 -129.000758 180)
		(property "Reference" "PR275"
			(at 0 0 0)
			(layer "B.SilkS")
			(hide yes)
			(effects
				(font
					(size 1.27 1.27)
				)
				(justify mirror)
			)
		)
		(property "Value" ""
			(at 0 0 0)
			(layer "B.Fab")
			(effects
				(font
					(size 1.27 1.27)
				)
				(justify mirror)
			)
		)
		(duplicate_pad_numbers_are_jumpers no)
		(fp_line
			(start 0.7874 0.4064)
			(end 0.7874 -0.4064)
			(stroke
				(width 0.1524)
				(type default)
			)
			(layer "B.SilkS")
		)
		(fp_line
			(start 0.7874 -0.4064)
			(end -0.7874 -0.4064)
			(stroke
				(width 0.1524)
				(type default)
			)
			(layer "B.SilkS")
		)
		(fp_line
			(start -0.7874 0.4064)
			(end 0.7874 0.4064)
			(stroke
				(width 0.1524)
				(type default)
			)
			(layer "B.SilkS")
		)
		(fp_line
			(start -0.7874 -0.4064)
			(end -0.7874 0.4064)
			(stroke
				(width 0.1524)
				(type default)
			)
			(layer "B.SilkS")
		)
		(fp_line
			(start 0.67945 0.3048)
			(end 0.67945 -0.305054)
			(stroke
				(width 0.1)
				(type default)
			)
			(layer "B.Fab")
		)
		(fp_line
			(start 0.67945 -0.305054)
			(end 0.12065 -0.305054)
			(stroke
				(width 0.1)
				(type default)
			)
			(layer "B.Fab")
		)
		(fp_line
			(start 0.12065 0.3048)
			(end 0.67945 0.3048)
			(stroke
				(width 0.1)
				(type default)
			)
			(layer "B.Fab")
		)
		(fp_line
			(start 0.12065 0.2794)
			(end 0.12065 0.3048)
			(stroke
				(width 0.1)
				(type default)
			)
			(layer "B.Fab")
		)
		(fp_line
			(start 0.12065 -0.2794)
			(end -0.12065 -0.2794)
			(stroke
				(width 0.1)
				(type default)
			)
			(layer "B.Fab")
		)
		(fp_line
			(start 0.12065 -0.305054)
			(end 0.12065 -0.2794)
			(stroke
				(width 0.1)
				(type default)
			)
			(layer "B.Fab")
		)
		(fp_line
			(start -0.120396 0.3048)
			(end -0.120396 0.2794)
			(stroke
				(width 0.1)
				(type default)
			)
			(layer "B.Fab")
		)
		(fp_line
			(start -0.120396 0.2794)
			(end 0.12065 0.2794)
			(stroke
				(width 0.1)
				(type default)
			)
			(layer "B.Fab")
		)
		(fp_line
			(start -0.12065 -0.2794)
			(end -0.12065 -0.3048)
			(stroke
				(width 0.1)
				(type default)
			)
			(layer "B.Fab")
		)
		(fp_line
			(start -0.12065 -0.3048)
			(end -0.67945 -0.3048)
			(stroke
				(width 0.1)
				(type default)
			)
			(layer "B.Fab")
		)
		(fp_line
			(start -0.67945 0.3048)
			(end -0.120396 0.3048)
			(stroke
				(width 0.1)
				(type default)
			)
			(layer "B.Fab")
		)
		(fp_line
			(start -0.67945 -0.3048)
			(end -0.67945 0.3048)
			(stroke
				(width 0.1)
				(type default)
			)
			(layer "B.Fab")
		)
		(pad "1" smd circle
			(at 0.40005 0)
			(size 0 0)
			(layers "B.Cu" "B.Mask" "B.Paste")
			(net "PVCCINFAON_CPU1_CSPIN")
		)
		(pad "2" smd circle
			(at -0.40005 0)
			(size 0 0)
			(layers "B.Cu" "B.Mask" "B.Paste")
			(net "GND")
		)
	)
	(footprint ""
		(layer "B.Cu")
		(at 77.90688 -11.267948 -90)
		(property "Reference" "R413"
			(at 0 0 90)
			(layer "B.SilkS")
			(hide yes)
			(effects
				(font
					(size 1.27 1.27)
				)
				(justify mirror)
			)
		)
		(property "Value" ""
			(at 0 0 90)
			(layer "B.Fab")
			(effects
				(font
					(size 1.27 1.27)
				)
				(justify mirror)
			)
		)
		(duplicate_pad_numbers_are_jumpers no)
		(fp_line
			(start -0.7874 0.4064)
			(end 0.7874 0.4064)
			(stroke
				(width 0.1524)
				(type default)
			)
			(layer "B.SilkS")
		)
		(fp_line
			(start 0.7874 0.4064)
			(end 0.7874 -0.4064)
			(stroke
				(width 0.1524)
				(type default)
			)
			(layer "B.SilkS")
		)
		(fp_line
			(start -0.7874 -0.4064)
			(end -0.7874 0.4064)
			(stroke
				(width 0.1524)
				(type default)
			)
			(layer "B.SilkS")
		)
		(fp_line
			(start 0.7874 -0.4064)
			(end -0.7874 -0.4064)
			(stroke
				(width 0.1524)
				(type default)
			)
			(layer "B.SilkS")
		)
		(fp_line
			(start -0.67945 0.3048)
			(end -0.120396 0.3048)
			(stroke
				(width 0.1)
				(type default)
			)
			(layer "B.Fab")
		)
		(fp_line
			(start -0.120396 0.3048)
			(end -0.120396 0.2794)
			(stroke
				(width 0.1)
				(type default)
			)
			(layer "B.Fab")
		)
		(fp_line
			(start 0.12065 0.3048)
			(end 0.67945 0.3048)
			(stroke
				(width 0.1)
				(type default)
			)
			(layer "B.Fab")
		)
		(fp_line
			(start 0.67945 0.3048)
			(end 0.67945 -0.305054)
			(stroke
				(width 0.1)
				(type default)
			)
			(layer "B.Fab")
		)
		(fp_line
			(start -0.120396 0.2794)
			(end 0.12065 0.2794)
			(stroke
				(width 0.1)
				(type default)
			)
			(layer "B.Fab")
		)
		(fp_line
			(start 0.12065 0.2794)
			(end 0.12065 0.3048)
			(stroke
				(width 0.1)
				(type default)
			)
			(layer "B.Fab")
		)
		(fp_line
			(start -0.12065 -0.2794)
			(end -0.12065 -0.3048)
			(stroke
				(width 0.1)
				(type default)
			)
			(layer "B.Fab")
		)
		(fp_line
			(start 0.12065 -0.2794)
			(end -0.12065 -0.2794)
			(stroke
				(width 0.1)
				(type default)
			)
			(layer "B.Fab")
		)
		(fp_line
			(start -0.67945 -0.3048)
			(end -0.67945 0.3048)
			(stroke
				(width 0.1)
				(type default)
			)
			(layer "B.Fab")
		)
		(fp_line
			(start -0.12065 -0.3048)
			(end -0.67945 -0.3048)
			(stroke
				(width 0.1)
				(type default)
			)
			(layer "B.Fab")
		)
		(fp_line
			(start 0.12065 -0.305054)
			(end 0.12065 -0.2794)
			(stroke
				(width 0.1)
				(type default)
			)
			(layer "B.Fab")
		)
		(fp_line
			(start 0.67945 -0.305054)
			(end 0.12065 -0.305054)
			(stroke
				(width 0.1)
				(type default)
			)
			(layer "B.Fab")
		)
		(pad "1" smd circle
			(at 0.40005 0 90)
			(size 0 0)
			(layers "B.Cu" "B.Mask" "B.Paste")
			(net "GND")
		)
		(pad "2" smd circle
			(at -0.40005 0 90)
			(size 0 0)
			(layers "B.Cu" "B.Mask" "B.Paste")
			(net "FM_OCP_V3_2_PWR_GOOD")
		)
	)
	(footprint ""
		(layer "B.Cu")
		(at 188.190886 -193.599816 -90)
		(property "Reference" "R704"
			(at 0 0 90)
			(layer "B.SilkS")
			(hide yes)
			(effects
				(font
					(size 1.27 1.27)
				)
				(justify mirror)
			)
		)
		(property "Value" ""
			(at 0 0 90)
			(layer "B.Fab")
			(effects
				(font
					(size 1.27 1.27)
				)
				(justify mirror)
			)
		)
		(duplicate_pad_numbers_are_jumpers no)
		(fp_line
			(start -0.7874 0.4064)
			(end 0.7874 0.4064)
			(stroke
				(width 0.1524)
				(type default)
			)
			(layer "B.SilkS")
		)
		(fp_line
			(start 0.7874 0.4064)
			(end 0.7874 -0.4064)
			(stroke
				(width 0.1524)
				(type default)
			)
			(layer "B.SilkS")
		)
		(fp_line
			(start -0.7874 -0.4064)
			(end -0.7874 0.4064)
			(stroke
				(width 0.1524)
				(type default)
			)
			(layer "B.SilkS")
		)
		(fp_line
			(start 0.7874 -0.4064)
			(end -0.7874 -0.4064)
			(stroke
				(width 0.1524)
				(type default)
			)
			(layer "B.SilkS")
		)
		(fp_line
			(start -0.67945 0.3048)
			(end -0.120396 0.3048)
			(stroke
				(width 0.1)
				(type default)
			)
			(layer "B.Fab")
		)
		(fp_line
			(start -0.120396 0.3048)
			(end -0.120396 0.2794)
			(stroke
				(width 0.1)
				(type default)
			)
			(layer "B.Fab")
		)
		(fp_line
			(start 0.12065 0.3048)
			(end 0.67945 0.3048)
			(stroke
				(width 0.1)
				(type default)
			)
			(layer "B.Fab")
		)
		(fp_line
			(start 0.67945 0.3048)
			(end 0.67945 -0.305054)
			(stroke
				(width 0.1)
				(type default)
			)
			(layer "B.Fab")
		)
		(fp_line
			(start -0.120396 0.2794)
			(end 0.12065 0.2794)
			(stroke
				(width 0.1)
				(type default)
			)
			(layer "B.Fab")
		)
		(fp_line
			(start 0.12065 0.2794)
			(end 0.12065 0.3048)
			(stroke
				(width 0.1)
				(type default)
			)
			(layer "B.Fab")
		)
		(fp_line
			(start -0.12065 -0.2794)
			(end -0.12065 -0.3048)
			(stroke
				(width 0.1)
				(type default)
			)
			(layer "B.Fab")
		)
		(fp_line
			(start 0.12065 -0.2794)
			(end -0.12065 -0.2794)
			(stroke
				(width 0.1)
				(type default)
			)
			(layer "B.Fab")
		)
		(fp_line
			(start -0.67945 -0.3048)
			(end -0.67945 0.3048)
			(stroke
				(width 0.1)
				(type default)
			)
			(layer "B.Fab")
		)
		(fp_line
			(start -0.12065 -0.3048)
			(end -0.67945 -0.3048)
			(stroke
				(width 0.1)
				(type default)
			)
			(layer "B.Fab")
		)
		(fp_line
			(start 0.12065 -0.305054)
			(end 0.12065 -0.2794)
			(stroke
				(width 0.1)
				(type default)
			)
			(layer "B.Fab")
		)
		(fp_line
			(start 0.67945 -0.305054)
			(end 0.12065 -0.305054)
			(stroke
				(width 0.1)
				(type default)
			)
			(layer "B.Fab")
		)
		(pad "1" smd circle
			(at 0.40005 0 90)
			(size 0 0)
			(layers "B.Cu" "B.Mask" "B.Paste")
			(net "RST_PLD_CPU1_DRAM_EF_N")
		)
		(pad "2" smd circle
			(at -0.40005 0 90)
			(size 0 0)
			(layers "B.Cu" "B.Mask" "B.Paste")
			(net "GND")
		)
	)
	(footprint ""
		(layer "B.Cu")
		(at 376.83694 -130.90906)
		(property "Reference" "ME14"
			(at 9.652 -9.540748 0)
			(unlocked yes)
			(layer "B.SilkS")
			(effects
				(font
					(size 0.7874 0.5842)
					(thickness 0.1524)
				)
				(justify left mirror)
			)
		)
		(property "Value" ""
			(at 0 0 0)
			(layer "B.Fab")
			(effects
				(font
					(size 1.27 1.27)
				)
				(justify mirror)
			)
		)
		(duplicate_pad_numbers_are_jumpers no)
		(zone
			(layer "B.Cu")
			(hatch none 0.5)
			(connect_pads
				(clearance 0)
			)
			(min_thickness 0.25)
			(keepout
				(tracks allowed)
				(vias allowed)
				(pads allowed)
				(copperpour allowed)
				(footprints not_allowed)
			)
			(placement
				(enabled no)
				(sheetname "")
			)
			(fill
				(thermal_gap 0.5)
				(thermal_bridge_width 0.5)
				(island_removal_mode 0)
			)
			(polygon
				(pts
					(arc
						(start 386.83692 -130.90906)
						(mid 366.83696 -130.90906)
						(end 386.83692 -130.90906)
					)
				)
			)
		)
	)
	(footprint ""
		(layer "B.Cu")
		(at 175.469804 -344.941906 -90)
		(property "Reference" "PC412_P1_1"
			(at 0 0 90)
			(layer "B.SilkS")
			(hide yes)
			(effects
				(font
					(size 1.27 1.27)
				)
				(justify mirror)
			)
		)
		(property "Value" ""
			(at 0 0 90)
			(layer "B.Fab")
			(effects
				(font
					(size 1.27 1.27)
				)
				(justify mirror)
			)
		)
		(duplicate_pad_numbers_are_jumpers no)
		(fp_line
			(start -1.524 0.762)
			(end 1.524 0.762)
			(stroke
				(width 0.1524)
				(type default)
			)
			(layer "B.SilkS")
		)
		(fp_line
			(start 1.524 0.762)
			(end 1.524 -0.762)
			(stroke
				(width 0.1524)
				(type default)
			)
			(layer "B.SilkS")
		)
		(fp_line
			(start -1.524 -0.762)
			(end -1.524 0.762)
			(stroke
				(width 0.1524)
				(type default)
			)
			(layer "B.SilkS")
		)
		(fp_line
			(start 1.524 -0.762)
			(end -1.524 -0.762)
			(stroke
				(width 0.1524)
				(type default)
			)
			(layer "B.SilkS")
		)
		(fp_line
			(start -1.1049 0.724916)
			(end -1.1049 -0.724916)
			(stroke
				(width 0.1)
				(type default)
			)
			(layer "B.Fab")
		)
		(fp_line
			(start 1.1049 0.724916)
			(end -1.1049 0.724916)
			(stroke
				(width 0.1)
				(type default)
			)
			(layer "B.Fab")
		)
		(fp_line
			(start -1.1049 -0.724916)
			(end 1.1049 -0.724916)
			(stroke
				(width 0.1)
				(type default)
			)
			(layer "B.Fab")
		)
		(fp_line
			(start 1.1049 -0.724916)
			(end 1.1049 0.724916)
			(stroke
				(width 0.1)
				(type default)
			)
			(layer "B.Fab")
		)
		(pad "1" smd rect
			(at 0.889 0 270)
			(size 1.016 1.27)
			(layers "B.Cu" "B.Mask" "B.Paste")
			(net "PVCCFA_EHV_FIVRA_CPU1")
		)
		(pad "2" smd rect
			(at -0.889 0 270)
			(size 1.016 1.27)
			(layers "B.Cu" "B.Mask" "B.Paste")
			(net "GND")
		)
	)
	(footprint ""
		(layer "B.Cu")
		(at 239.091724 -97.084642 180)
		(property "Reference" "L13"
			(at 0 0 0)
			(layer "B.SilkS")
			(hide yes)
			(effects
				(font
					(size 1.27 1.27)
				)
				(justify mirror)
			)
		)
		(property "Value" ""
			(at 0 0 0)
			(layer "B.Fab")
			(effects
				(font
					(size 1.27 1.27)
				)
				(justify mirror)
			)
		)
		(duplicate_pad_numbers_are_jumpers no)
		(fp_line
			(start 1.63576 -0.8128)
			(end 1.63576 0.8128)
			(stroke
				(width 0.1524)
				(type default)
			)
			(layer "B.SilkS")
		)
		(fp_line
			(start 1.63576 -0.8128)
			(end -1.63576 -0.8128)
			(stroke
				(width 0.1524)
				(type default)
			)
			(layer "B.SilkS")
		)
		(fp_line
			(start -1.63576 0.8128)
			(end 1.63576 0.8128)
			(stroke
				(width 0.1524)
				(type default)
			)
			(layer "B.SilkS")
		)
		(fp_line
			(start -1.63576 -0.8128)
			(end -1.63576 0.8128)
			(stroke
				(width 0.1524)
				(type default)
			)
			(layer "B.SilkS")
		)
		(fp_line
			(start 1.56083 0.7366)
			(end 1.524 0.7366)
			(stroke
				(width 0.1)
				(type default)
			)
			(layer "B.Fab")
		)
		(fp_line
			(start 1.56083 -0.738632)
			(end 1.56083 0.7366)
			(stroke
				(width 0.1)
				(type default)
			)
			(layer "B.Fab")
		)
		(fp_line
			(start 1.524 0.7366)
			(end -1.524 0.7366)
			(stroke
				(width 0.1)
				(type default)
			)
			(layer "B.Fab")
		)
		(fp_line
			(start -1.524 0.7366)
			(end -1.560576 0.7366)
			(stroke
				(width 0.1)
				(type default)
			)
			(layer "B.Fab")
		)
		(fp_line
			(start -1.560576 0.7366)
			(end -1.560576 -0.738632)
			(stroke
				(width 0.1)
				(type default)
			)
			(layer "B.Fab")
		)
		(fp_line
			(start -1.560576 -0.738632)
			(end 1.56083 -0.738632)
			(stroke
				(width 0.1)
				(type default)
			)
			(layer "B.Fab")
		)
		(pad "1" smd rect
			(at 0.94996 0 180)
			(size 1.1176 1.3716)
			(layers "B.Cu" "B.Mask" "B.Paste")
			(net "P3V3_AUX")
		)
		(pad "2" smd rect
			(at -0.94996 0 180)
			(size 1.1176 1.3716)
			(layers "B.Cu" "B.Mask" "B.Paste")
			(net "P3V3_AUX_CLK_GEN_VDDXTAL_CK440")
		)
	)
	(footprint ""
		(layer "B.Cu")
		(at 363.2962 -356.094792)
		(property "Reference" "R2589"
			(at 0 0 0)
			(layer "B.SilkS")
			(hide yes)
			(effects
				(font
					(size 1.27 1.27)
				)
				(justify mirror)
			)
		)
		(property "Value" ""
			(at 0 0 0)
			(layer "B.Fab")
			(effects
				(font
					(size 1.27 1.27)
				)
				(justify mirror)
			)
		)
		(duplicate_pad_numbers_are_jumpers no)
		(fp_line
			(start -0.7874 -0.4064)
			(end -0.7874 0.4064)
			(stroke
				(width 0.1524)
				(type default)
			)
			(layer "B.SilkS")
		)
		(fp_line
			(start -0.7874 0.4064)
			(end 0.7874 0.4064)
			(stroke
				(width 0.1524)
				(type default)
			)
			(layer "B.SilkS")
		)
		(fp_line
			(start 0.7874 -0.4064)
			(end -0.7874 -0.4064)
			(stroke
				(width 0.1524)
				(type default)
			)
			(layer "B.SilkS")
		)
		(fp_line
			(start 0.7874 0.4064)
			(end 0.7874 -0.4064)
			(stroke
				(width 0.1524)
				(type default)
			)
			(layer "B.SilkS")
		)
		(fp_line
			(start -0.67945 -0.3048)
			(end -0.67945 0.3048)
			(stroke
				(width 0.1)
				(type default)
			)
			(layer "B.Fab")
		)
		(fp_line
			(start -0.67945 0.3048)
			(end -0.120396 0.3048)
			(stroke
				(width 0.1)
				(type default)
			)
			(layer "B.Fab")
		)
		(fp_line
			(start -0.12065 -0.3048)
			(end -0.67945 -0.3048)
			(stroke
				(width 0.1)
				(type default)
			)
			(layer "B.Fab")
		)
		(fp_line
			(start -0.12065 -0.2794)
			(end -0.12065 -0.3048)
			(stroke
				(width 0.1)
				(type default)
			)
			(layer "B.Fab")
		)
		(fp_line
			(start -0.120396 0.2794)
			(end 0.12065 0.2794)
			(stroke
				(width 0.1)
				(type default)
			)
			(layer "B.Fab")
		)
		(fp_line
			(start -0.120396 0.3048)
			(end -0.120396 0.2794)
			(stroke
				(width 0.1)
				(type default)
			)
			(layer "B.Fab")
		)
		(fp_line
			(start 0.12065 -0.305054)
			(end 0.12065 -0.2794)
			(stroke
				(width 0.1)
				(type default)
			)
			(layer "B.Fab")
		)
		(fp_line
			(start 0.12065 -0.2794)
			(end -0.12065 -0.2794)
			(stroke
				(width 0.1)
				(type default)
			)
			(layer "B.Fab")
		)
		(fp_line
			(start 0.12065 0.2794)
			(end 0.12065 0.3048)
			(stroke
				(width 0.1)
				(type default)
			)
			(layer "B.Fab")
		)
		(fp_line
			(start 0.12065 0.3048)
			(end 0.67945 0.3048)
			(stroke
				(width 0.1)
				(type default)
			)
			(layer "B.Fab")
		)
		(fp_line
			(start 0.67945 -0.305054)
			(end 0.12065 -0.305054)
			(stroke
				(width 0.1)
				(type default)
			)
			(layer "B.Fab")
		)
		(fp_line
			(start 0.67945 0.3048)
			(end 0.67945 -0.305054)
			(stroke
				(width 0.1)
				(type default)
			)
			(layer "B.Fab")
		)
		(pad "1" smd circle
			(at 0.40005 0 180)
			(size 0 0)
			(layers "B.Cu" "B.Mask" "B.Paste")
			(net "P3V3_AUX")
		)
		(pad "2" smd circle
			(at -0.40005 0 180)
			(size 0 0)
			(layers "B.Cu" "B.Mask" "B.Paste")
			(net "PVCCIN_CPU0_VR_FAULT")
		)
	)
	(footprint ""
		(layer "B.Cu")
		(at 139.021058 -347.008704 -90)
		(property "Reference" "PC491_P1_8"
			(at 0 0 90)
			(layer "B.SilkS")
			(hide yes)
			(effects
				(font
					(size 1.27 1.27)
				)
				(justify mirror)
			)
		)
		(property "Value" ""
			(at 0 0 90)
			(layer "B.Fab")
			(effects
				(font
					(size 1.27 1.27)
				)
				(justify mirror)
			)
		)
		(duplicate_pad_numbers_are_jumpers no)
		(fp_line
			(start -1.524 0.762)
			(end 1.524 0.762)
			(stroke
				(width 0.1524)
				(type default)
			)
			(layer "B.SilkS")
		)
		(fp_line
			(start 1.524 0.762)
			(end 1.524 -0.762)
			(stroke
				(width 0.1524)
				(type default)
			)
			(layer "B.SilkS")
		)
		(fp_line
			(start -1.524 -0.762)
			(end -1.524 0.762)
			(stroke
				(width 0.1524)
				(type default)
			)
			(layer "B.SilkS")
		)
		(fp_line
			(start 1.524 -0.762)
			(end -1.524 -0.762)
			(stroke
				(width 0.1524)
				(type default)
			)
			(layer "B.SilkS")
		)
		(fp_line
			(start -1.1049 0.724916)
			(end -1.1049 -0.724916)
			(stroke
				(width 0.1)
				(type default)
			)
			(layer "B.Fab")
		)
		(fp_line
			(start 1.1049 0.724916)
			(end -1.1049 0.724916)
			(stroke
				(width 0.1)
				(type default)
			)
			(layer "B.Fab")
		)
		(fp_line
			(start -1.1049 -0.724916)
			(end 1.1049 -0.724916)
			(stroke
				(width 0.1)
				(type default)
			)
			(layer "B.Fab")
		)
		(fp_line
			(start 1.1049 -0.724916)
			(end 1.1049 0.724916)
			(stroke
				(width 0.1)
				(type default)
			)
			(layer "B.Fab")
		)
		(pad "1" smd rect
			(at 0.889 0 270)
			(size 1.016 1.27)
			(layers "B.Cu" "B.Mask" "B.Paste")
			(net "SW_P12V_PVCCIN_CPU1_FLT")
		)
		(pad "2" smd rect
			(at -0.889 0 270)
			(size 1.016 1.27)
			(layers "B.Cu" "B.Mask" "B.Paste")
			(net "GND")
		)
	)
)
